# T6G (Grand Teton) — schematic netlist excerpt (pin names and nets, part order shuffled) for the footprints in the layout excerpt that follows; sources: Cadence DE-HDL packaged netlist, KiCad conversion of 04192023_DAF0TMB3IC0_F0TG_MB_C_brd_V02_OCP.brd

R1359  Q_RES  0 5% CHIP  pkg 0402LF  page 81 : A = BMC_JTAG_SEL_R ; B = BMC_JTAG_SEL
C886  Q_CAP_DIFFBUS  DIFF BUS_0.22UF 6.3V 20% X6S  pkg C0201  page 64 : \1\ = P5E_CPU0_P3_TX_C_DN<7> ; \2\ = P5E_CPU0_P3_TX_DN<7>
R4520  Q_RES  10K 1% CHIP  pkg 0402LF  page 182 : A = FM_9ZXL045_P0_0_OE_N ; B = GND

(kicad_pcb
	(version 20260206)
	(generator "pcbnew")
	(generator_version "10.0")
	(general
		(thickness 1.6)
		(legacy_teardrops no)
	)
	(paper "A4")
	(title_block
		(title "04192023_DAF0TMB3IC0_F0TG_MB_C_brd_V02_OCP.brd")
		(comment 1 "Grand Teton / footprints 500-502 of 8354")
	)
	(layers
		(0 "F.Cu" signal "TOP")
		(4 "In1.Cu" signal "GND")
		(6 "In2.Cu" signal "IN1")
		(8 "In3.Cu" signal "GND1")
		(10 "In4.Cu" signal "IN2")
		(12 "In5.Cu" signal "GND2")
		(14 "In6.Cu" signal "IN3")
		(16 "In7.Cu" signal "GND3")
		(18 "In8.Cu" signal "VCC")
		(20 "In9.Cu" signal "VCC1")
		(22 "In10.Cu" signal "GND4")
		(24 "In11.Cu" signal "IN4")
		(26 "In12.Cu" signal "GND5")
		(28 "In13.Cu" signal "IN5")
		(30 "In14.Cu" signal "GND6")
		(32 "In15.Cu" signal "IN6")
		(34 "In16.Cu" signal "GND7")
		(2 "B.Cu" signal "BOTTOM")
		(9 "F.Adhes" user "F.Adhesive")
		(11 "B.Adhes" user "B.Adhesive")
		(13 "F.Paste" user "Package Geometry/Pastemask Top")
		(15 "B.Paste" user "Package Geometry/Pastemask Bottom")
		(5 "F.SilkS" user "Ref Des/Silkscreen Top")
		(7 "B.SilkS" user "Ref Des/Silkscreen Bottom")
		(1 "F.Mask" user "Board Geometry/Soldermask Top")
		(3 "B.Mask" user "Board Geometry/Soldermask Bottom")
		(17 "Dwgs.User" user "User.Drawings")
		(19 "Cmts.User" user "User.Comments")
		(21 "Eco1.User" user "User.Eco1")
		(23 "Eco2.User" user "User.Eco2")
		(25 "Edge.Cuts" user "Board Geometry/Outline")
		(27 "Margin" user)
		(31 "F.CrtYd" user "Package Geometry/Place Bound Top")
		(29 "B.CrtYd" user "Package Geometry/Place Bound Bottom")
		(35 "F.Fab" user "Ref Des/Assembly Top")
		(33 "B.Fab" user "Ref Des/Assembly Bottom")
	)
	(footprint ""
		(layer "F.Cu")
		(at 191.135 -129.377948 90)
		(property "Reference" "R1359"
			(at 0 0 90)
			(layer "F.SilkS")
			(hide yes)
			(effects
				(font
					(size 1.27 1.27)
				)
			)
		)
		(property "Value" ""
			(at 0 0 90)
			(layer "F.Fab")
			(effects
				(font
					(size 1.27 1.27)
				)
			)
		)
		(duplicate_pad_numbers_are_jumpers no)
		(fp_line
			(start 0.7874 -0.4064)
			(end 0.7874 0.4064)
			(stroke
				(width 0.1524)
				(type default)
			)
			(layer "F.SilkS")
		)
		(fp_line
			(start -0.7874 -0.4064)
			(end 0.7874 -0.4064)
			(stroke
				(width 0.1524)
				(type default)
			)
			(layer "F.SilkS")
		)
		(fp_line
			(start 0.7874 0.4064)
			(end -0.7874 0.4064)
			(stroke
				(width 0.1524)
				(type default)
			)
			(layer "F.SilkS")
		)
		(fp_line
			(start -0.7874 0.4064)
			(end -0.7874 -0.4064)
			(stroke
				(width 0.1524)
				(type default)
			)
			(layer "F.SilkS")
		)
		(fp_line
			(start -0.12065 -0.305054)
			(end -0.12065 -0.2794)
			(stroke
				(width 0.1)
				(type default)
			)
			(layer "F.Fab")
		)
		(fp_line
			(start -0.67945 -0.305054)
			(end -0.12065 -0.305054)
			(stroke
				(width 0.1)
				(type default)
			)
			(layer "F.Fab")
		)
		(fp_line
			(start 0.67945 -0.3048)
			(end 0.67945 0.3048)
			(stroke
				(width 0.1)
				(type default)
			)
			(layer "F.Fab")
		)
		(fp_line
			(start 0.12065 -0.3048)
			(end 0.67945 -0.3048)
			(stroke
				(width 0.1)
				(type default)
			)
			(layer "F.Fab")
		)
		(fp_line
			(start 0.12065 -0.2794)
			(end 0.12065 -0.3048)
			(stroke
				(width 0.1)
				(type default)
			)
			(layer "F.Fab")
		)
		(fp_line
			(start -0.12065 -0.2794)
			(end 0.12065 -0.2794)
			(stroke
				(width 0.1)
				(type default)
			)
			(layer "F.Fab")
		)
		(fp_line
			(start 0.120396 0.2794)
			(end -0.12065 0.2794)
			(stroke
				(width 0.1)
				(type default)
			)
			(layer "F.Fab")
		)
		(fp_line
			(start -0.12065 0.2794)
			(end -0.12065 0.3048)
			(stroke
				(width 0.1)
				(type default)
			)
			(layer "F.Fab")
		)
		(fp_line
			(start 0.67945 0.3048)
			(end 0.120396 0.3048)
			(stroke
				(width 0.1)
				(type default)
			)
			(layer "F.Fab")
		)
		(fp_line
			(start 0.120396 0.3048)
			(end 0.120396 0.2794)
			(stroke
				(width 0.1)
				(type default)
			)
			(layer "F.Fab")
		)
		(fp_line
			(start -0.12065 0.3048)
			(end -0.67945 0.3048)
			(stroke
				(width 0.1)
				(type default)
			)
			(layer "F.Fab")
		)
		(fp_line
			(start -0.67945 0.3048)
			(end -0.67945 -0.305054)
			(stroke
				(width 0.1)
				(type default)
			)
			(layer "F.Fab")
		)
		(pad "1" smd circle
			(at -0.40005 0 90)
			(size 0 0)
			(layers "F.Cu" "F.Mask" "F.Paste")
			(net "BMC_JTAG_SEL_R")
		)
		(pad "2" smd circle
			(at 0.40005 0 90)
			(size 0 0)
			(layers "F.Cu" "F.Mask" "F.Paste")
			(net "BMC_JTAG_SEL")
		)
	)
	(footprint ""
		(layer "F.Cu")
		(at 287.570672 -412.74111 -90)
		(property "Reference" "R4520"
			(at 0 0 270)
			(layer "F.SilkS")
			(hide yes)
			(effects
				(font
					(size 1.27 1.27)
				)
			)
		)
		(property "Value" ""
			(at 0 0 270)
			(layer "F.Fab")
			(effects
				(font
					(size 1.27 1.27)
				)
			)
		)
		(duplicate_pad_numbers_are_jumpers no)
		(fp_line
			(start -0.7874 0.4064)
			(end -0.7874 -0.4064)
			(stroke
				(width 0.1524)
				(type default)
			)
			(layer "F.SilkS")
		)
		(fp_line
			(start 0.7874 0.4064)
			(end -0.7874 0.4064)
			(stroke
				(width 0.1524)
				(type default)
			)
			(layer "F.SilkS")
		)
		(fp_line
			(start -0.7874 -0.4064)
			(end 0.7874 -0.4064)
			(stroke
				(width 0.1524)
				(type default)
			)
			(layer "F.SilkS")
		)
		(fp_line
			(start 0.7874 -0.4064)
			(end 0.7874 0.4064)
			(stroke
				(width 0.1524)
				(type default)
			)
			(layer "F.SilkS")
		)
		(fp_line
			(start -0.67945 0.3048)
			(end -0.67945 -0.305054)
			(stroke
				(width 0.1)
				(type default)
			)
			(layer "F.Fab")
		)
		(fp_line
			(start -0.12065 0.3048)
			(end -0.67945 0.3048)
			(stroke
				(width 0.1)
				(type default)
			)
			(layer "F.Fab")
		)
		(fp_line
			(start 0.120396 0.3048)
			(end 0.120396 0.2794)
			(stroke
				(width 0.1)
				(type default)
			)
			(layer "F.Fab")
		)
		(fp_line
			(start 0.67945 0.3048)
			(end 0.120396 0.3048)
			(stroke
				(width 0.1)
				(type default)
			)
			(layer "F.Fab")
		)
		(fp_line
			(start -0.12065 0.2794)
			(end -0.12065 0.3048)
			(stroke
				(width 0.1)
				(type default)
			)
			(layer "F.Fab")
		)
		(fp_line
			(start 0.120396 0.2794)
			(end -0.12065 0.2794)
			(stroke
				(width 0.1)
				(type default)
			)
			(layer "F.Fab")
		)
		(fp_line
			(start -0.12065 -0.2794)
			(end 0.12065 -0.2794)
			(stroke
				(width 0.1)
				(type default)
			)
			(layer "F.Fab")
		)
		(fp_line
			(start 0.12065 -0.2794)
			(end 0.12065 -0.3048)
			(stroke
				(width 0.1)
				(type default)
			)
			(layer "F.Fab")
		)
		(fp_line
			(start 0.12065 -0.3048)
			(end 0.67945 -0.3048)
			(stroke
				(width 0.1)
				(type default)
			)
			(layer "F.Fab")
		)
		(fp_line
			(start 0.67945 -0.3048)
			(end 0.67945 0.3048)
			(stroke
				(width 0.1)
				(type default)
			)
			(layer "F.Fab")
		)
		(fp_line
			(start -0.67945 -0.305054)
			(end -0.12065 -0.305054)
			(stroke
				(width 0.1)
				(type default)
			)
			(layer "F.Fab")
		)
		(fp_line
			(start -0.12065 -0.305054)
			(end -0.12065 -0.2794)
			(stroke
				(width 0.1)
				(type default)
			)
			(layer "F.Fab")
		)
		(pad "1" smd circle
			(at -0.40005 0 270)
			(size 0 0)
			(layers "F.Cu" "F.Mask" "F.Paste")
			(net "FM_9ZXL045_P0_0_OE_N")
		)
		(pad "2" smd circle
			(at 0.40005 0 270)
			(size 0 0)
			(layers "F.Cu" "F.Mask" "F.Paste")
			(net "GND")
		)
	)
	(footprint ""
		(layer "F.Cu")
		(at 378.916692 -383.88163 -90)
		(property "Reference" "C886"
			(at 0 0 270)
			(layer "F.SilkS")
			(hide yes)
			(effects
				(font
					(size 1.27 1.27)
				)
			)
		)
		(property "Value" ""
			(at 0 0 270)
			(layer "F.Fab")
			(effects
				(font
					(size 1.27 1.27)
				)
			)
		)
		(duplicate_pad_numbers_are_jumpers no)
		(fp_line
			(start -0.299974 0.150114)
			(end -0.299974 -0.150114)
			(stroke
				(width 0.1)
				(type default)
			)
			(layer "F.Fab")
		)
		(fp_line
			(start 0.299974 0.150114)
			(end -0.299974 0.150114)
			(stroke
				(width 0.1)
				(type default)
			)
			(layer "F.Fab")
		)
		(fp_line
			(start -0.299974 -0.150114)
			(end 0.299974 -0.150114)
			(stroke
				(width 0.1)
				(type default)
			)
			(layer "F.Fab")
		)
		(fp_line
			(start 0.299974 -0.150114)
			(end 0.299974 0.150114)
			(stroke
				(width 0.1)
				(type default)
			)
			(layer "F.Fab")
		)
		(pad "1" smd rect
			(at -0.2667 0 270)
			(size 0.3048 0.381)
			(layers "F.Cu" "F.Mask" "F.Paste")
			(net "P5E_CPU0_P3_TX_C_DN<7>")
		)
		(pad "2" smd rect
			(at 0.2667 0 270)
			(size 0.3048 0.381)
			(layers "F.Cu" "F.Mask" "F.Paste")
			(net "P5E_CPU0_P3_TX_DN<7>")
		)
	)
)
